(kicad_pcb
	(version 20260206)
	(generator "pcbnew")
	(generator_version "10.0")
	(general
		(thickness 1.6)
		(legacy_teardrops no)
	)
	(paper "A4")
	(title_block
		(title "Bryce Canyon_R.DPB_16317-1_OCP.brd")
		(comment 1 "Bryce Canyon / footprint 274 of 2099 (SAS1), pads 71-144 of 342")
	)
	(layers
		(0 "F.Cu" signal "TOP")
		(4 "In1.Cu" signal "L2GND")
		(6 "In2.Cu" signal "L3")
		(8 "In3.Cu" signal "L4VCC")
		(10 "In4.Cu" signal "L5VCC")
		(12 "In5.Cu" signal "L6")
		(14 "In6.Cu" signal "L7GND")
		(2 "B.Cu" signal "BOTTOM")
		(9 "F.Adhes" user "F.Adhesive")
		(11 "B.Adhes" user "B.Adhesive")
		(13 "F.Paste" user "Package Geometry/Pastemask Top")
		(15 "B.Paste" user "Package Geometry/Pastemask Bottom")
		(5 "F.SilkS" user "Ref Des/Silkscreen Top")
		(7 "B.SilkS" user "Ref Des/Silkscreen Bottom")
		(1 "F.Mask" user "Board Geometry/Soldermask Top")
		(3 "B.Mask" user "Board Geometry/Soldermask Bottom")
		(17 "Dwgs.User" user "User.Drawings")
		(19 "Cmts.User" user "User.Comments")
		(21 "Eco1.User" user "User.Eco1")
		(23 "Eco2.User" user "User.Eco2")
		(25 "Edge.Cuts" user "Board Geometry/Outline")
		(27 "Margin" user)
		(31 "F.CrtYd" user "Package Geometry/Place Bound Top")
		(29 "B.CrtYd" user "Package Geometry/Place Bound Bottom")
		(35 "F.Fab" user "Ref Des/Assembly Top")
		(33 "B.Fab" user "Ref Des/Assembly Bottom")
	)
	(footprint ""
		(layer "F.Cu")
		(at 287.83661 -238.694468 -90)
		(property "Reference" "SAS1"
			(at 0 0 270)
			(layer "F.SilkS")
			(hide yes)
			(effects
				(font
					(size 1.27 1.27)
				)
			)
		)
		(property "Value" "AMP-CONN342-10R-2-GP"
			(at 20.955 -16.7386 270)
			(unlocked yes)
			(layer "F.Fab")
			(hide yes)
			(effects
				(font
					(size 1.016 1.016)
					(thickness 0.1524)
				)
			)
		)
		(property "Device Type" "PREFIT-342P-668151H483"
			(at 20.955 -18.2626 270)
			(unlocked yes)
			(layer "F.Fab")
			(hide yes)
			(effects
				(font
					(size 1.016 1.016)
					(thickness 0.1524)
				)
			)
		)
		(duplicate_pad_numbers_are_jumpers no)
		(pad "B35" thru_hole circle
			(at 61.20003 1.400048 270)
			(size 0.762 0.762)
			(drill 0.359918)
			(layers "*.Cu" "*.Mask")
			(remove_unused_layers no)
			(net "PHY_DRV_B_TO_SCC_B_31_DP")
			(clearance 0.1651)
			(thermal_gap 0.1651)
		)
		(pad "B36" thru_hole circle
			(at 62.999874 2.400046 270)
			(size 0.762 0.762)
			(drill 0.359918)
			(layers "*.Cu" "*.Mask")
			(remove_unused_layers no)
			(net "PHY_DRV_B_TO_SCC_B_30_DP")
			(clearance 0.1651)
			(thermal_gap 0.1651)
		)
		(pad "C1" thru_hole circle
			(at 0 3.599942 270)
			(size 0.762 0.762)
			(drill 0.359918)
			(layers "*.Cu" "*.Mask")
			(remove_unused_layers no)
			(net "SCC_B_STBY_PGOOD")
			(clearance 0.1651)
			(thermal_gap 0.1651)
		)
		(pad "C2" thru_hole circle
			(at 1.800098 4.59994 270)
			(size 0.762 0.762)
			(drill 0.359918)
			(layers "*.Cu" "*.Mask")
			(remove_unused_layers no)
			(net "P3V3_STBY_B")
			(clearance 0.1651)
			(thermal_gap 0.1651)
		)
		(pad "C3" thru_hole circle
			(at 3.599942 3.599942 270)
			(size 0.762 0.762)
			(drill 0.359918)
			(layers "*.Cu" "*.Mask")
			(remove_unused_layers no)
			(net "SCC_B_HEARTBEAT")
			(clearance 0.1651)
			(thermal_gap 0.1651)
		)
		(pad "C4" thru_hole circle
			(at 5.40004 4.59994 270)
			(size 0.762 0.762)
			(drill 0.359918)
			(layers "*.Cu" "*.Mask")
			(remove_unused_layers no)
			(net "SCC_B_SLOT_ID_0")
			(clearance 0.1651)
			(thermal_gap 0.1651)
		)
		(pad "C5" thru_hole circle
			(at 7.199884 3.599942 270)
			(size 0.762 0.762)
			(drill 0.359918)
			(layers "*.Cu" "*.Mask")
			(remove_unused_layers no)
			(net "SCC_B_TYPE_0")
			(clearance 0.1651)
			(thermal_gap 0.1651)
		)
		(pad "C6" thru_hole circle
			(at 8.999982 4.59994 270)
			(size 0.762 0.762)
			(drill 0.359918)
			(layers "*.Cu" "*.Mask")
			(remove_unused_layers no)
			(net "SCC_B_TYPE_2")
			(clearance 0.1651)
			(thermal_gap 0.1651)
		)
		(pad "C7" thru_hole circle
			(at 10.80008 3.599942 270)
			(size 0.762 0.762)
			(drill 0.359918)
			(layers "*.Cu" "*.Mask")
			(remove_unused_layers no)
			(net "UART_SDB_B_TX")
			(clearance 0.1651)
			(thermal_gap 0.1651)
		)
		(pad "C8" thru_hole circle
			(at 12.599924 4.59994 270)
			(size 0.762 0.762)
			(drill 0.359918)
			(layers "*.Cu" "*.Mask")
			(remove_unused_layers no)
			(net "PWM_SCC_B_ZONE_C")
			(clearance 0.1651)
			(thermal_gap 0.1651)
		)
		(pad "C9" thru_hole circle
			(at 14.400022 3.599942 270)
			(size 0.762 0.762)
			(drill 0.359918)
			(layers "*.Cu" "*.Mask")
			(remove_unused_layers no)
			(net "SCC_B_PWR_LED")
			(clearance 0.1651)
			(thermal_gap 0.1651)
		)
		(pad "C10" thru_hole circle
			(at 16.20012 4.59994 270)
			(size 0.762 0.762)
			(drill 0.359918)
			(layers "*.Cu" "*.Mask")
			(remove_unused_layers no)
			(net "SCC_B_FAULT_LED")
			(clearance 0.1651)
			(thermal_gap 0.1651)
		)
		(pad "C11" thru_hole circle
			(at 17.999964 3.599942 270)
			(size 0.762 0.762)
			(drill 0.359918)
			(layers "*.Cu" "*.Mask")
			(remove_unused_layers no)
			(net "DRIVE_INSERT_ALERT_B_N")
			(clearance 0.1651)
			(thermal_gap 0.1651)
		)
		(pad "C12" thru_hole circle
			(at 19.800062 4.59994 270)
			(size 0.762 0.762)
			(drill 0.359918)
			(layers "*.Cu" "*.Mask")
			(remove_unused_layers no)
			(net "I2C_CLIP_B_SCL")
			(clearance 0.1651)
			(thermal_gap 0.1651)
		)
		(pad "C13" thru_hole circle
			(at 21.599906 3.599942 270)
			(size 0.762 0.762)
			(drill 0.359918)
			(layers "*.Cu" "*.Mask")
			(remove_unused_layers no)
			(net "UART_EXP_B_TX")
			(clearance 0.1651)
			(thermal_gap 0.1651)
		)
		(pad "C14" thru_hole circle
			(at 23.400004 4.59994 270)
			(size 0.762 0.762)
			(drill 0.359918)
			(layers "*.Cu" "*.Mask")
			(remove_unused_layers no)
			(net "I2C_DPB_B_SCL_BUF")
			(clearance 0.1651)
			(thermal_gap 0.1651)
		)
		(pad "C15" thru_hole circle
			(at 25.200102 3.599942 270)
			(size 0.762 0.762)
			(drill 0.359918)
			(layers "*.Cu" "*.Mask")
			(remove_unused_layers no)
			(net "I2C_DRIVE_B_PWR_SCL")
			(clearance 0.1651)
			(thermal_gap 0.1651)
		)
		(pad "C16" thru_hole circle
			(at 26.999946 4.59994 270)
			(size 0.762 0.762)
			(drill 0.359918)
			(layers "*.Cu" "*.Mask")
			(remove_unused_layers no)
			(net "I2C_DRIVE_B_INS_SCL")
			(clearance 0.1651)
			(thermal_gap 0.1651)
		)
		(pad "C17" thru_hole circle
			(at 28.800044 3.599942 270)
			(size 0.762 0.762)
			(drill 0.359918)
			(layers "*.Cu" "*.Mask")
			(remove_unused_layers no)
			(net "I2C_DRIVE_B_FLT_LED_SCL")
			(clearance 0.1651)
			(thermal_gap 0.1651)
		)
		(pad "C18" thru_hole circle
			(at 30.599888 4.59994 270)
			(size 0.762 0.762)
			(drill 0.359918)
			(layers "*.Cu" "*.Mask")
			(remove_unused_layers no)
			(net "DRIVE_B_0_ACT")
			(clearance 0.1651)
			(thermal_gap 0.1651)
		)
		(pad "C19" thru_hole circle
			(at 32.399986 3.599942 270)
			(size 0.762 0.762)
			(drill 0.359918)
			(layers "*.Cu" "*.Mask")
			(remove_unused_layers no)
			(net "DRIVE_B_2_ACT")
			(clearance 0.1651)
			(thermal_gap 0.1651)
		)
		(pad "C20" thru_hole circle
			(at 34.200084 4.59994 270)
			(size 0.762 0.762)
			(drill 0.359918)
			(layers "*.Cu" "*.Mask")
			(remove_unused_layers no)
			(net "DRIVE_B_4_ACT")
			(clearance 0.1651)
			(thermal_gap 0.1651)
		)
		(pad "C21" thru_hole circle
			(at 35.999928 3.599942 270)
			(size 0.762 0.762)
			(drill 0.359918)
			(layers "*.Cu" "*.Mask")
			(remove_unused_layers no)
			(net "DRIVE_B_6_ACT")
			(clearance 0.1651)
			(thermal_gap 0.1651)
		)
		(pad "C22" thru_hole circle
			(at 37.800026 4.59994 270)
			(size 0.762 0.762)
			(drill 0.359918)
			(layers "*.Cu" "*.Mask")
			(remove_unused_layers no)
			(net "DRIVE_B_8_ACT")
			(clearance 0.1651)
			(thermal_gap 0.1651)
		)
		(pad "C23" thru_hole circle
			(at 39.600124 3.599942 270)
			(size 0.762 0.762)
			(drill 0.359918)
			(layers "*.Cu" "*.Mask")
			(remove_unused_layers no)
			(net "DRIVE_B_10_ACT")
			(clearance 0.1651)
			(thermal_gap 0.1651)
		)
		(pad "C24" thru_hole circle
			(at 41.399968 4.59994 270)
			(size 0.762 0.762)
			(drill 0.359918)
			(layers "*.Cu" "*.Mask")
			(remove_unused_layers no)
			(net "DRIVE_B_12_ACT")
			(clearance 0.1651)
			(thermal_gap 0.1651)
		)
		(pad "C25" thru_hole circle
			(at 43.200066 3.599942 270)
			(size 0.762 0.762)
			(drill 0.359918)
			(layers "*.Cu" "*.Mask")
			(remove_unused_layers no)
			(net "DRIVE_B_14_ACT")
			(clearance 0.1651)
			(thermal_gap 0.1651)
		)
		(pad "C26" thru_hole circle
			(at 44.99991 4.59994 270)
			(size 0.762 0.762)
			(drill 0.359918)
			(layers "*.Cu" "*.Mask")
			(remove_unused_layers no)
			(net "DRIVE_B_16_ACT")
			(clearance 0.1651)
			(thermal_gap 0.1651)
		)
		(pad "C27" thru_hole circle
			(at 46.800008 3.599942 270)
			(size 0.762 0.762)
			(drill 0.359918)
			(layers "*.Cu" "*.Mask")
			(remove_unused_layers no)
			(net "DRIVE_B_18_ACT")
			(clearance 0.1651)
			(thermal_gap 0.1651)
		)
		(pad "C28" thru_hole circle
			(at 48.600106 4.59994 270)
			(size 0.762 0.762)
			(drill 0.359918)
			(layers "*.Cu" "*.Mask")
			(remove_unused_layers no)
			(net "DRIVE_B_20_ACT")
			(clearance 0.1651)
			(thermal_gap 0.1651)
		)
		(pad "C29" thru_hole circle
			(at 50.39995 3.599942 270)
			(size 0.762 0.762)
			(drill 0.359918)
			(layers "*.Cu" "*.Mask")
			(remove_unused_layers no)
			(net "DRIVE_B_22_ACT")
			(clearance 0.1651)
			(thermal_gap 0.1651)
		)
		(pad "C30" thru_hole circle
			(at 52.200048 4.59994 270)
			(size 0.762 0.762)
			(drill 0.359918)
			(layers "*.Cu" "*.Mask")
			(remove_unused_layers no)
			(net "DRIVE_B_24_ACT")
			(clearance 0.1651)
			(thermal_gap 0.1651)
		)
		(pad "C31" thru_hole circle
			(at 53.999892 3.599942 270)
			(size 0.762 0.762)
			(drill 0.359918)
			(layers "*.Cu" "*.Mask")
			(remove_unused_layers no)
			(net "DRIVE_B_26_ACT")
			(clearance 0.1651)
			(thermal_gap 0.1651)
		)
		(pad "C32" thru_hole circle
			(at 55.79999 4.59994 270)
			(size 0.762 0.762)
			(drill 0.359918)
			(layers "*.Cu" "*.Mask")
			(remove_unused_layers no)
			(net "DRIVE_B_28_ACT")
			(clearance 0.1651)
			(thermal_gap 0.1651)
		)
		(pad "C33" thru_hole circle
			(at 57.600088 3.599942 270)
			(size 0.762 0.762)
			(drill 0.359918)
			(layers "*.Cu" "*.Mask")
			(remove_unused_layers no)
			(net "DRIVE_B_30_ACT")
			(clearance 0.1651)
			(thermal_gap 0.1651)
		)
		(pad "C34" thru_hole circle
			(at 59.399932 4.59994 270)
			(size 0.762 0.762)
			(drill 0.359918)
			(layers "*.Cu" "*.Mask")
			(remove_unused_layers no)
			(net "DRIVE_B_32_ACT")
			(clearance 0.1651)
			(thermal_gap 0.1651)
		)
		(pad "C35" thru_hole circle
			(at 61.20003 3.599942 270)
			(size 0.762 0.762)
			(drill 0.359918)
			(layers "*.Cu" "*.Mask")
			(remove_unused_layers no)
			(net "DRIVE_B_34_ACT")
			(clearance 0.1651)
			(thermal_gap 0.1651)
		)
		(pad "C36" thru_hole circle
			(at 62.999874 4.59994 270)
			(size 0.762 0.762)
			(drill 0.359918)
			(layers "*.Cu" "*.Mask")
			(remove_unused_layers no)
			(net "SCC_B_HS_EN")
			(clearance 0.1651)
			(thermal_gap 0.1651)
		)
		(pad "D1" thru_hole circle
			(at 0 4.99999 270)
			(size 0.762 0.762)
			(drill 0.359918)
			(layers "*.Cu" "*.Mask")
			(remove_unused_layers no)
			(net "BMC_B_HEARTBEAT")
			(clearance 0.1651)
			(thermal_gap 0.1651)
		)
		(pad "D2" thru_hole circle
			(at 1.800098 5.999988 270)
			(size 0.762 0.762)
			(drill 0.359918)
			(layers "*.Cu" "*.Mask")
			(remove_unused_layers no)
			(net "SCC_B_STBY_PWR_EN")
			(clearance 0.1651)
			(thermal_gap 0.1651)
		)
		(pad "D3" thru_hole circle
			(at 3.599942 4.99999 270)
			(size 0.762 0.762)
			(drill 0.359918)
			(layers "*.Cu" "*.Mask")
			(remove_unused_layers no)
			(net "SCC_A_HEARTBEAT")
			(clearance 0.1651)
			(thermal_gap 0.1651)
		)
		(pad "D4" thru_hole circle
			(at 5.40004 5.999988 270)
			(size 0.762 0.762)
			(drill 0.359918)
			(layers "*.Cu" "*.Mask")
			(remove_unused_layers no)
			(net "SCC_B_SLOT_ID_1")
			(clearance 0.1651)
			(thermal_gap 0.1651)
		)
		(pad "D5" thru_hole circle
			(at 7.199884 4.99999 270)
			(size 0.762 0.762)
			(drill 0.359918)
			(layers "*.Cu" "*.Mask")
			(remove_unused_layers no)
			(net "SCC_B_TYPE_1")
			(clearance 0.1651)
			(thermal_gap 0.1651)
		)
		(pad "D6" thru_hole circle
			(at 8.999982 5.999988 270)
			(size 0.762 0.762)
			(drill 0.359918)
			(layers "*.Cu" "*.Mask")
			(remove_unused_layers no)
			(net "SCC_B_TYPE_3")
			(clearance 0.1651)
			(thermal_gap 0.1651)
		)
		(pad "D7" thru_hole circle
			(at 10.80008 4.99999 270)
			(size 0.762 0.762)
			(drill 0.359918)
			(layers "*.Cu" "*.Mask")
			(remove_unused_layers no)
			(net "UART_SDB_B_RX")
			(clearance 0.1651)
			(thermal_gap 0.1651)
		)
		(pad "D8" thru_hole circle
			(at 12.599924 5.999988 270)
			(size 0.762 0.762)
			(drill 0.359918)
			(layers "*.Cu" "*.Mask")
			(remove_unused_layers no)
			(net "PWM_SCC_B_ZONE_D")
			(clearance 0.1651)
			(thermal_gap 0.1651)
		)
		(pad "D9" thru_hole circle
			(at 14.400022 4.99999 270)
			(size 0.762 0.762)
			(drill 0.359918)
			(layers "*.Cu" "*.Mask")
			(remove_unused_layers no)
			(net "SCC_B_FULL_PWR_EN")
			(clearance 0.1651)
			(thermal_gap 0.1651)
		)
		(pad "D10" thru_hole circle
			(at 16.20012 5.999988 270)
			(size 0.762 0.762)
			(drill 0.359918)
			(layers "*.Cu" "*.Mask")
			(remove_unused_layers no)
			(net "SCC_B_RESET_N")
			(clearance 0.1651)
			(thermal_gap 0.1651)
		)
		(pad "D11" thru_hole circle
			(at 17.999964 4.99999 270)
			(size 0.762 0.762)
			(drill 0.359918)
			(layers "*.Cu" "*.Mask")
			(remove_unused_layers no)
			(net "SCC_B_INS_N")
			(clearance 0.1651)
			(thermal_gap 0.1651)
		)
		(pad "D12" thru_hole circle
			(at 19.800062 5.999988 270)
			(size 0.762 0.762)
			(drill 0.359918)
			(layers "*.Cu" "*.Mask")
			(remove_unused_layers no)
			(net "I2C_CLIP_B_SDA")
			(clearance 0.1651)
			(thermal_gap 0.1651)
		)
		(pad "D13" thru_hole circle
			(at 21.599906 4.99999 270)
			(size 0.762 0.762)
			(drill 0.359918)
			(layers "*.Cu" "*.Mask")
			(remove_unused_layers no)
			(net "UART_EXP_B_RX")
			(clearance 0.1651)
			(thermal_gap 0.1651)
		)
		(pad "D14" thru_hole circle
			(at 23.400004 5.999988 270)
			(size 0.762 0.762)
			(drill 0.359918)
			(layers "*.Cu" "*.Mask")
			(remove_unused_layers no)
			(net "I2C_DPB_B_SDA_BUF")
			(clearance 0.1651)
			(thermal_gap 0.1651)
		)
		(pad "D15" thru_hole circle
			(at 25.200102 4.99999 270)
			(size 0.762 0.762)
			(drill 0.359918)
			(layers "*.Cu" "*.Mask")
			(remove_unused_layers no)
			(net "I2C_DRIVE_B_PWR_SDA")
			(clearance 0.1651)
			(thermal_gap 0.1651)
		)
		(pad "D16" thru_hole circle
			(at 26.999946 5.999988 270)
			(size 0.762 0.762)
			(drill 0.359918)
			(layers "*.Cu" "*.Mask")
			(remove_unused_layers no)
			(net "I2C_DRIVE_B_INS_SDA")
			(clearance 0.1651)
			(thermal_gap 0.1651)
		)
		(pad "D17" thru_hole circle
			(at 28.800044 4.99999 270)
			(size 0.762 0.762)
			(drill 0.359918)
			(layers "*.Cu" "*.Mask")
			(remove_unused_layers no)
			(net "I2C_DRIVE_B_FLT_LED_SDA")
			(clearance 0.1651)
			(thermal_gap 0.1651)
		)
		(pad "D18" thru_hole circle
			(at 30.599888 5.999988 270)
			(size 0.762 0.762)
			(drill 0.359918)
			(layers "*.Cu" "*.Mask")
			(remove_unused_layers no)
			(net "DRIVE_B_1_ACT")
			(clearance 0.1651)
			(thermal_gap 0.1651)
		)
		(pad "D19" thru_hole circle
			(at 32.399986 4.99999 270)
			(size 0.762 0.762)
			(drill 0.359918)
			(layers "*.Cu" "*.Mask")
			(remove_unused_layers no)
			(net "DRIVE_B_3_ACT")
			(clearance 0.1651)
			(thermal_gap 0.1651)
		)
		(pad "D20" thru_hole circle
			(at 34.200084 5.999988 270)
			(size 0.762 0.762)
			(drill 0.359918)
			(layers "*.Cu" "*.Mask")
			(remove_unused_layers no)
			(net "DRIVE_B_5_ACT")
			(clearance 0.1651)
			(thermal_gap 0.1651)
		)
		(pad "D21" thru_hole circle
			(at 35.999928 4.99999 270)
			(size 0.762 0.762)
			(drill 0.359918)
			(layers "*.Cu" "*.Mask")
			(remove_unused_layers no)
			(net "DRIVE_B_7_ACT")
			(clearance 0.1651)
			(thermal_gap 0.1651)
		)
		(pad "D22" thru_hole circle
			(at 37.800026 5.999988 270)
			(size 0.762 0.762)
			(drill 0.359918)
			(layers "*.Cu" "*.Mask")
			(remove_unused_layers no)
			(net "DRIVE_B_9_ACT")
			(clearance 0.1651)
			(thermal_gap 0.1651)
		)
		(pad "D23" thru_hole circle
			(at 39.600124 4.99999 270)
			(size 0.762 0.762)
			(drill 0.359918)
			(layers "*.Cu" "*.Mask")
			(remove_unused_layers no)
			(net "DRIVE_B_11_ACT")
			(clearance 0.1651)
			(thermal_gap 0.1651)
		)
		(pad "D24" thru_hole circle
			(at 41.399968 5.999988 270)
			(size 0.762 0.762)
			(drill 0.359918)
			(layers "*.Cu" "*.Mask")
			(remove_unused_layers no)
			(net "DRIVE_B_13_ACT")
			(clearance 0.1651)
			(thermal_gap 0.1651)
		)
		(pad "D25" thru_hole circle
			(at 43.200066 4.99999 270)
			(size 0.762 0.762)
			(drill 0.359918)
			(layers "*.Cu" "*.Mask")
			(remove_unused_layers no)
			(net "DRIVE_B_15_ACT")
			(clearance 0.1651)
			(thermal_gap 0.1651)
		)
		(pad "D26" thru_hole circle
			(at 44.99991 5.999988 270)
			(size 0.762 0.762)
			(drill 0.359918)
			(layers "*.Cu" "*.Mask")
			(remove_unused_layers no)
			(net "DRIVE_B_17_ACT")
			(clearance 0.1651)
			(thermal_gap 0.1651)
		)
		(pad "D27" thru_hole circle
			(at 46.800008 4.99999 270)
			(size 0.762 0.762)
			(drill 0.359918)
			(layers "*.Cu" "*.Mask")
			(remove_unused_layers no)
			(net "DRIVE_B_19_ACT")
			(clearance 0.1651)
			(thermal_gap 0.1651)
		)
		(pad "D28" thru_hole circle
			(at 48.600106 5.999988 270)
			(size 0.762 0.762)
			(drill 0.359918)
			(layers "*.Cu" "*.Mask")
			(remove_unused_layers no)
			(net "DRIVE_B_21_ACT")
			(clearance 0.1651)
			(thermal_gap 0.1651)
		)
		(pad "D29" thru_hole circle
			(at 50.39995 4.99999 270)
			(size 0.762 0.762)
			(drill 0.359918)
			(layers "*.Cu" "*.Mask")
			(remove_unused_layers no)
			(net "DRIVE_B_23_ACT")
			(clearance 0.1651)
			(thermal_gap 0.1651)
		)
		(pad "D30" thru_hole circle
			(at 52.200048 5.999988 270)
			(size 0.762 0.762)
			(drill 0.359918)
			(layers "*.Cu" "*.Mask")
			(remove_unused_layers no)
			(net "DRIVE_B_25_ACT")
			(clearance 0.1651)
			(thermal_gap 0.1651)
		)
		(pad "D31" thru_hole circle
			(at 53.999892 4.99999 270)
			(size 0.762 0.762)
			(drill 0.359918)
			(layers "*.Cu" "*.Mask")
			(remove_unused_layers no)
			(net "DRIVE_B_27_ACT")
			(clearance 0.1651)
			(thermal_gap 0.1651)
		)
		(pad "D32" thru_hole circle
			(at 55.79999 5.999988 270)
			(size 0.762 0.762)
			(drill 0.359918)
			(layers "*.Cu" "*.Mask")
			(remove_unused_layers no)
			(net "DRIVE_B_29_ACT")
			(clearance 0.1651)
			(thermal_gap 0.1651)
		)
		(pad "D33" thru_hole circle
			(at 57.600088 4.99999 270)
			(size 0.762 0.762)
			(drill 0.359918)
			(layers "*.Cu" "*.Mask")
			(remove_unused_layers no)
			(net "DRIVE_B_31_ACT")
			(clearance 0.1651)
			(thermal_gap 0.1651)
		)
		(pad "D34" thru_hole circle
			(at 59.399932 5.999988 270)
			(size 0.762 0.762)
			(drill 0.359918)
			(layers "*.Cu" "*.Mask")
			(remove_unused_layers no)
			(net "DRIVE_B_33_ACT")
			(clearance 0.1651)
			(thermal_gap 0.1651)
		)
		(pad "D35" thru_hole circle
			(at 61.20003 4.99999 270)
			(size 0.762 0.762)
			(drill 0.359918)
			(layers "*.Cu" "*.Mask")
			(remove_unused_layers no)
			(net "DRIVE_B_35_ACT")
			(clearance 0.1651)
			(thermal_gap 0.1651)
		)
		(pad "D36" thru_hole circle
			(at 62.999874 5.999988 270)
			(size 0.762 0.762)
			(drill 0.359918)
			(layers "*.Cu" "*.Mask")
			(remove_unused_layers no)
			(net "SCC_B_FULL_PGOOD")
			(clearance 0.1651)
			(thermal_gap 0.1651)
		)
	)
)
